# S9S_MB_2U (Grand Teton) — schematic netlist excerpt (pin names and nets, part order shuffled) for the footprints in the layout excerpt that follows; sources: Cadence DE-HDL packaged netlist, KiCad conversion of 03242023_DA0F0TMBIJ0_F0T_Motherboard_J_brd_V01_OCP.brd

C468  Q_CAP  47UF 4V 20% X6S  pkg C0805  page 79 : A = PVCCFA_EHV_CPU1 ; B = GND
PR1299  Q_RES  2.2 1% CHIP  pkg 0402LF  page 272 : A = PVCCFA_EHV_FIVRA_CPU0_PVCC1 ; B = PVCCFA_EHV_FIVRA_CPU0_VDD3
C97  Q_CAP  10UF 16V 10% X6S  pkg C0805  page 105 : A = P12V_S3_AUX_CPU1_NVDIMM ; B = GND

(kicad_pcb
	(version 20260206)
	(generator "pcbnew")
	(generator_version "10.0")
	(general
		(thickness 1.6)
		(legacy_teardrops no)
	)
	(paper "A4")
	(title_block
		(title "03242023_DA0F0TMBIJ0_F0T_Motherboard_J_brd_V01_OCP.brd")
		(comment 1 "Grand Teton / footprints 4841-4843 of 6105")
	)
	(layers
		(0 "F.Cu" signal "TOP")
		(4 "In1.Cu" signal "GND")
		(6 "In2.Cu" signal "IN1")
		(8 "In3.Cu" signal "GND1")
		(10 "In4.Cu" signal "IN2")
		(12 "In5.Cu" signal "GND2")
		(14 "In6.Cu" signal "IN3")
		(16 "In7.Cu" signal "GND3")
		(18 "In8.Cu" signal "VCC")
		(20 "In9.Cu" signal "VCC1")
		(22 "In10.Cu" signal "GND4")
		(24 "In11.Cu" signal "IN4")
		(26 "In12.Cu" signal "GND5")
		(28 "In13.Cu" signal "IN5")
		(30 "In14.Cu" signal "GND6")
		(32 "In15.Cu" signal "IN6")
		(34 "In16.Cu" signal "GND7")
		(2 "B.Cu" signal "BOTTOM")
		(9 "F.Adhes" user "F.Adhesive")
		(11 "B.Adhes" user "B.Adhesive")
		(13 "F.Paste" user "Package Geometry/Pastemask Top")
		(15 "B.Paste" user "Package Geometry/Pastemask Bottom")
		(5 "F.SilkS" user "Ref Des/Silkscreen Top")
		(7 "B.SilkS" user "Ref Des/Silkscreen Bottom")
		(1 "F.Mask" user "Board Geometry/Soldermask Top")
		(3 "B.Mask" user "Board Geometry/Soldermask Bottom")
		(17 "Dwgs.User" user "User.Drawings")
		(19 "Cmts.User" user "User.Comments")
		(21 "Eco1.User" user "User.Eco1")
		(23 "Eco2.User" user "User.Eco2")
		(25 "Edge.Cuts" user "Board Geometry/Outline")
		(27 "Margin" user)
		(31 "F.CrtYd" user "Package Geometry/Place Bound Top")
		(29 "B.CrtYd" user "Package Geometry/Place Bound Bottom")
		(35 "F.Fab" user "Ref Des/Assembly Top")
		(33 "B.Fab" user "Ref Des/Assembly Bottom")
	)
	(footprint ""
		(layer "B.Cu")
		(at 107.887008 -210.194144 180)
		(property "Reference" "C468"
			(at 0 0 0)
			(layer "B.SilkS")
			(hide yes)
			(effects
				(font
					(size 1.27 1.27)
				)
				(justify mirror)
			)
		)
		(property "Value" ""
			(at 0 0 0)
			(layer "B.Fab")
			(effects
				(font
					(size 1.27 1.27)
				)
				(justify mirror)
			)
		)
		(duplicate_pad_numbers_are_jumpers no)
		(fp_line
			(start 1.524 0.762)
			(end 1.524 -0.762)
			(stroke
				(width 0.1524)
				(type default)
			)
			(layer "B.SilkS")
		)
		(fp_line
			(start 1.524 -0.762)
			(end -1.524 -0.762)
			(stroke
				(width 0.1524)
				(type default)
			)
			(layer "B.SilkS")
		)
		(fp_line
			(start -1.524 0.762)
			(end 1.524 0.762)
			(stroke
				(width 0.1524)
				(type default)
			)
			(layer "B.SilkS")
		)
		(fp_line
			(start -1.524 -0.762)
			(end -1.524 0.762)
			(stroke
				(width 0.1524)
				(type default)
			)
			(layer "B.SilkS")
		)
		(fp_line
			(start 1.1049 0.724916)
			(end -1.1049 0.724916)
			(stroke
				(width 0.1)
				(type default)
			)
			(layer "B.Fab")
		)
		(fp_line
			(start 1.1049 -0.724916)
			(end 1.1049 0.724916)
			(stroke
				(width 0.1)
				(type default)
			)
			(layer "B.Fab")
		)
		(fp_line
			(start -1.1049 0.724916)
			(end -1.1049 -0.724916)
			(stroke
				(width 0.1)
				(type default)
			)
			(layer "B.Fab")
		)
		(fp_line
			(start -1.1049 -0.724916)
			(end 1.1049 -0.724916)
			(stroke
				(width 0.1)
				(type default)
			)
			(layer "B.Fab")
		)
		(pad "1" smd rect
			(at 0.889 0 180)
			(size 1.016 1.27)
			(layers "B.Cu" "B.Mask" "B.Paste")
			(net "PVCCFA_EHV_CPU1")
		)
		(pad "2" smd rect
			(at -0.889 0 180)
			(size 1.016 1.27)
			(layers "B.Cu" "B.Mask" "B.Paste")
			(net "GND")
		)
	)
	(footprint ""
		(layer "B.Cu")
		(at 19.760946 -321.554856 -90)
		(property "Reference" "C97"
			(at 0 0 90)
			(layer "B.SilkS")
			(hide yes)
			(effects
				(font
					(size 1.27 1.27)
				)
				(justify mirror)
			)
		)
		(property "Value" ""
			(at 0 0 90)
			(layer "B.Fab")
			(effects
				(font
					(size 1.27 1.27)
				)
				(justify mirror)
			)
		)
		(duplicate_pad_numbers_are_jumpers no)
		(fp_line
			(start -1.524 0.762)
			(end 1.524 0.762)
			(stroke
				(width 0.1524)
				(type default)
			)
			(layer "B.SilkS")
		)
		(fp_line
			(start 1.524 0.762)
			(end 1.524 -0.762)
			(stroke
				(width 0.1524)
				(type default)
			)
			(layer "B.SilkS")
		)
		(fp_line
			(start -1.524 -0.762)
			(end -1.524 0.762)
			(stroke
				(width 0.1524)
				(type default)
			)
			(layer "B.SilkS")
		)
		(fp_line
			(start 1.524 -0.762)
			(end -1.524 -0.762)
			(stroke
				(width 0.1524)
				(type default)
			)
			(layer "B.SilkS")
		)
		(fp_line
			(start -1.1049 0.724916)
			(end -1.1049 -0.724916)
			(stroke
				(width 0.1)
				(type default)
			)
			(layer "B.Fab")
		)
		(fp_line
			(start 1.1049 0.724916)
			(end -1.1049 0.724916)
			(stroke
				(width 0.1)
				(type default)
			)
			(layer "B.Fab")
		)
		(fp_line
			(start -1.1049 -0.724916)
			(end 1.1049 -0.724916)
			(stroke
				(width 0.1)
				(type default)
			)
			(layer "B.Fab")
		)
		(fp_line
			(start 1.1049 -0.724916)
			(end 1.1049 0.724916)
			(stroke
				(width 0.1)
				(type default)
			)
			(layer "B.Fab")
		)
		(pad "1" smd rect
			(at 0.889 0 270)
			(size 1.016 1.27)
			(layers "B.Cu" "B.Mask" "B.Paste")
			(net "P12V_S3_AUX_CPU1_NVDIMM")
		)
		(pad "2" smd rect
			(at -0.889 0 270)
			(size 1.016 1.27)
			(layers "B.Cu" "B.Mask" "B.Paste")
			(net "GND")
		)
	)
	(footprint ""
		(layer "B.Cu")
		(at 422.939718 -363.098588 -90)
		(property "Reference" "PR1299"
			(at 0 0 90)
			(layer "B.SilkS")
			(hide yes)
			(effects
				(font
					(size 1.27 1.27)
				)
				(justify mirror)
			)
		)
		(property "Value" ""
			(at 0 0 90)
			(layer "B.Fab")
			(effects
				(font
					(size 1.27 1.27)
				)
				(justify mirror)
			)
		)
		(duplicate_pad_numbers_are_jumpers no)
		(fp_line
			(start -0.7874 0.4064)
			(end 0.7874 0.4064)
			(stroke
				(width 0.1524)
				(type default)
			)
			(layer "B.SilkS")
		)
		(fp_line
			(start 0.7874 0.4064)
			(end 0.7874 -0.4064)
			(stroke
				(width 0.1524)
				(type default)
			)
			(layer "B.SilkS")
		)
		(fp_line
			(start -0.7874 -0.4064)
			(end -0.7874 0.4064)
			(stroke
				(width 0.1524)
				(type default)
			)
			(layer "B.SilkS")
		)
		(fp_line
			(start 0.7874 -0.4064)
			(end -0.7874 -0.4064)
			(stroke
				(width 0.1524)
				(type default)
			)
			(layer "B.SilkS")
		)
		(fp_line
			(start -0.67945 0.3048)
			(end -0.120396 0.3048)
			(stroke
				(width 0.1)
				(type default)
			)
			(layer "B.Fab")
		)
		(fp_line
			(start -0.120396 0.3048)
			(end -0.120396 0.2794)
			(stroke
				(width 0.1)
				(type default)
			)
			(layer "B.Fab")
		)
		(fp_line
			(start 0.12065 0.3048)
			(end 0.67945 0.3048)
			(stroke
				(width 0.1)
				(type default)
			)
			(layer "B.Fab")
		)
		(fp_line
			(start 0.67945 0.3048)
			(end 0.67945 -0.305054)
			(stroke
				(width 0.1)
				(type default)
			)
			(layer "B.Fab")
		)
		(fp_line
			(start -0.120396 0.2794)
			(end 0.12065 0.2794)
			(stroke
				(width 0.1)
				(type default)
			)
			(layer "B.Fab")
		)
		(fp_line
			(start 0.12065 0.2794)
			(end 0.12065 0.3048)
			(stroke
				(width 0.1)
				(type default)
			)
			(layer "B.Fab")
		)
		(fp_line
			(start -0.12065 -0.2794)
			(end -0.12065 -0.3048)
			(stroke
				(width 0.1)
				(type default)
			)
			(layer "B.Fab")
		)
		(fp_line
			(start 0.12065 -0.2794)
			(end -0.12065 -0.2794)
			(stroke
				(width 0.1)
				(type default)
			)
			(layer "B.Fab")
		)
		(fp_line
			(start -0.67945 -0.3048)
			(end -0.67945 0.3048)
			(stroke
				(width 0.1)
				(type default)
			)
			(layer "B.Fab")
		)
		(fp_line
			(start -0.12065 -0.3048)
			(end -0.67945 -0.3048)
			(stroke
				(width 0.1)
				(type default)
			)
			(layer "B.Fab")
		)
		(fp_line
			(start 0.12065 -0.305054)
			(end 0.12065 -0.2794)
			(stroke
				(width 0.1)
				(type default)
			)
			(layer "B.Fab")
		)
		(fp_line
			(start 0.67945 -0.305054)
			(end 0.12065 -0.305054)
			(stroke
				(width 0.1)
				(type default)
			)
			(layer "B.Fab")
		)
		(pad "1" smd circle
			(at 0.40005 0 90)
			(size 0 0)
			(layers "B.Cu" "B.Mask" "B.Paste")
			(net "PVCCFA_EHV_FIVRA_CPU0_PVCC1")
		)
		(pad "2" smd circle
			(at -0.40005 0 90)
			(size 0 0)
			(layers "B.Cu" "B.Mask" "B.Paste")
			(net "PVCCFA_EHV_FIVRA_CPU0_VDD3")
		)
	)
)
